(kicad_pcb
	(version 20260206)
	(generator "pcbnew")
	(generator_version "10.0")
	(general
		(thickness 1.6)
		(legacy_teardrops no)
	)
	(paper "A4")
	(title_block
		(title "9052_F0T_PDB_Converter_Brick_F_V03_1208_1600_OCP.brd")
		(comment 1 "Grand Teton / footprints 572-577 of 578")
	)
	(layers
		(0 "F.Cu" signal "TOP")
		(4 "In1.Cu" signal "GND")
		(6 "In2.Cu" signal "IN1")
		(8 "In3.Cu" signal "GND1")
		(10 "In4.Cu" signal "VCC")
		(12 "In5.Cu" signal "VCC1")
		(14 "In6.Cu" signal "GND2")
		(16 "In7.Cu" signal "IN2")
		(18 "In8.Cu" signal "GND3")
		(2 "B.Cu" signal "BOTTOM")
		(9 "F.Adhes" user "F.Adhesive")
		(11 "B.Adhes" user "B.Adhesive")
		(13 "F.Paste" user "Package Geometry/Pastemask Top")
		(15 "B.Paste" user "Package Geometry/Pastemask Bottom")
		(5 "F.SilkS" user "Ref Des/Silkscreen Top")
		(7 "B.SilkS" user "Ref Des/Silkscreen Bottom")
		(1 "F.Mask" user "Board Geometry/Soldermask Top")
		(3 "B.Mask" user "Board Geometry/Soldermask Bottom")
		(17 "Dwgs.User" user "User.Drawings")
		(19 "Cmts.User" user "User.Comments")
		(21 "Eco1.User" user "User.Eco1")
		(23 "Eco2.User" user "User.Eco2")
		(25 "Edge.Cuts" user "Board Geometry/Outline")
		(27 "Margin" user)
		(31 "F.CrtYd" user "Package Geometry/Place Bound Top")
		(29 "B.CrtYd" user "Package Geometry/Place Bound Bottom")
		(35 "F.Fab" user "Ref Des/Assembly Top")
		(33 "B.Fab" user "Ref Des/Assembly Bottom")
	)
	(footprint ""
		(layer "B.Cu")
		(at 274.955 -46.482 -90)
		(property "Reference" "R5907"
			(at 0 0 90)
			(layer "B.SilkS")
			(hide yes)
			(effects
				(font
					(size 1.27 1.27)
				)
				(justify mirror)
			)
		)
		(property "Value" ""
			(at 0 0 90)
			(layer "B.Fab")
			(effects
				(font
					(size 1.27 1.27)
				)
				(justify mirror)
			)
		)
		(duplicate_pad_numbers_are_jumpers no)
		(fp_line
			(start -0.7874 0.4064)
			(end 0.7874 0.4064)
			(stroke
				(width 0.1524)
				(type default)
			)
			(layer "B.SilkS")
		)
		(fp_line
			(start 0.7874 0.4064)
			(end 0.7874 -0.4064)
			(stroke
				(width 0.1524)
				(type default)
			)
			(layer "B.SilkS")
		)
		(fp_line
			(start -0.7874 -0.4064)
			(end -0.7874 0.4064)
			(stroke
				(width 0.1524)
				(type default)
			)
			(layer "B.SilkS")
		)
		(fp_line
			(start 0.7874 -0.4064)
			(end -0.7874 -0.4064)
			(stroke
				(width 0.1524)
				(type default)
			)
			(layer "B.SilkS")
		)
		(fp_line
			(start -0.67945 0.3048)
			(end -0.120396 0.3048)
			(stroke
				(width 0.1)
				(type default)
			)
			(layer "B.Fab")
		)
		(fp_line
			(start -0.120396 0.3048)
			(end -0.120396 0.2794)
			(stroke
				(width 0.1)
				(type default)
			)
			(layer "B.Fab")
		)
		(fp_line
			(start 0.12065 0.3048)
			(end 0.67945 0.3048)
			(stroke
				(width 0.1)
				(type default)
			)
			(layer "B.Fab")
		)
		(fp_line
			(start 0.67945 0.3048)
			(end 0.67945 -0.305054)
			(stroke
				(width 0.1)
				(type default)
			)
			(layer "B.Fab")
		)
		(fp_line
			(start -0.120396 0.2794)
			(end 0.12065 0.2794)
			(stroke
				(width 0.1)
				(type default)
			)
			(layer "B.Fab")
		)
		(fp_line
			(start 0.12065 0.2794)
			(end 0.12065 0.3048)
			(stroke
				(width 0.1)
				(type default)
			)
			(layer "B.Fab")
		)
		(fp_line
			(start -0.12065 -0.2794)
			(end -0.12065 -0.3048)
			(stroke
				(width 0.1)
				(type default)
			)
			(layer "B.Fab")
		)
		(fp_line
			(start 0.12065 -0.2794)
			(end -0.12065 -0.2794)
			(stroke
				(width 0.1)
				(type default)
			)
			(layer "B.Fab")
		)
		(fp_line
			(start -0.67945 -0.3048)
			(end -0.67945 0.3048)
			(stroke
				(width 0.1)
				(type default)
			)
			(layer "B.Fab")
		)
		(fp_line
			(start -0.12065 -0.3048)
			(end -0.67945 -0.3048)
			(stroke
				(width 0.1)
				(type default)
			)
			(layer "B.Fab")
		)
		(fp_line
			(start 0.12065 -0.305054)
			(end 0.12065 -0.2794)
			(stroke
				(width 0.1)
				(type default)
			)
			(layer "B.Fab")
		)
		(fp_line
			(start 0.67945 -0.305054)
			(end 0.12065 -0.305054)
			(stroke
				(width 0.1)
				(type default)
			)
			(layer "B.Fab")
		)
		(pad "1" smd circle
			(at 0.40005 0 90)
			(size 0 0)
			(layers "B.Cu" "B.Mask" "B.Paste")
			(net "P52V_HS1_ADR0")
		)
		(pad "2" smd circle
			(at -0.40005 0 90)
			(size 0 0)
			(layers "B.Cu" "B.Mask" "B.Paste")
			(net "GND_FIELD_SIGNAL")
		)
	)
	(footprint ""
		(layer "B.Cu")
		(at 215.265 -91.059 90)
		(property "Reference" "R33"
			(at 0 0 90)
			(layer "B.SilkS")
			(hide yes)
			(effects
				(font
					(size 1.27 1.27)
				)
				(justify mirror)
			)
		)
		(property "Value" ""
			(at 0 0 90)
			(layer "B.Fab")
			(effects
				(font
					(size 1.27 1.27)
				)
				(justify mirror)
			)
		)
		(duplicate_pad_numbers_are_jumpers no)
		(fp_line
			(start 0.7874 -0.4064)
			(end -0.7874 -0.4064)
			(stroke
				(width 0.1524)
				(type default)
			)
			(layer "B.SilkS")
		)
		(fp_line
			(start -0.7874 -0.4064)
			(end -0.7874 0.4064)
			(stroke
				(width 0.1524)
				(type default)
			)
			(layer "B.SilkS")
		)
		(fp_line
			(start 0.7874 0.4064)
			(end 0.7874 -0.4064)
			(stroke
				(width 0.1524)
				(type default)
			)
			(layer "B.SilkS")
		)
		(fp_line
			(start -0.7874 0.4064)
			(end 0.7874 0.4064)
			(stroke
				(width 0.1524)
				(type default)
			)
			(layer "B.SilkS")
		)
		(fp_line
			(start 0.67945 -0.305054)
			(end 0.12065 -0.305054)
			(stroke
				(width 0.1)
				(type default)
			)
			(layer "B.Fab")
		)
		(fp_line
			(start 0.12065 -0.305054)
			(end 0.12065 -0.2794)
			(stroke
				(width 0.1)
				(type default)
			)
			(layer "B.Fab")
		)
		(fp_line
			(start -0.12065 -0.3048)
			(end -0.67945 -0.3048)
			(stroke
				(width 0.1)
				(type default)
			)
			(layer "B.Fab")
		)
		(fp_line
			(start -0.67945 -0.3048)
			(end -0.67945 0.3048)
			(stroke
				(width 0.1)
				(type default)
			)
			(layer "B.Fab")
		)
		(fp_line
			(start 0.12065 -0.2794)
			(end -0.12065 -0.2794)
			(stroke
				(width 0.1)
				(type default)
			)
			(layer "B.Fab")
		)
		(fp_line
			(start -0.12065 -0.2794)
			(end -0.12065 -0.3048)
			(stroke
				(width 0.1)
				(type default)
			)
			(layer "B.Fab")
		)
		(fp_line
			(start 0.12065 0.2794)
			(end 0.12065 0.3048)
			(stroke
				(width 0.1)
				(type default)
			)
			(layer "B.Fab")
		)
		(fp_line
			(start -0.120396 0.2794)
			(end 0.12065 0.2794)
			(stroke
				(width 0.1)
				(type default)
			)
			(layer "B.Fab")
		)
		(fp_line
			(start 0.67945 0.3048)
			(end 0.67945 -0.305054)
			(stroke
				(width 0.1)
				(type default)
			)
			(layer "B.Fab")
		)
		(fp_line
			(start 0.12065 0.3048)
			(end 0.67945 0.3048)
			(stroke
				(width 0.1)
				(type default)
			)
			(layer "B.Fab")
		)
		(fp_line
			(start -0.120396 0.3048)
			(end -0.120396 0.2794)
			(stroke
				(width 0.1)
				(type default)
			)
			(layer "B.Fab")
		)
		(fp_line
			(start -0.67945 0.3048)
			(end -0.120396 0.3048)
			(stroke
				(width 0.1)
				(type default)
			)
			(layer "B.Fab")
		)
		(pad "1" smd circle
			(at 0.40005 0 270)
			(size 0 0)
			(layers "B.Cu" "B.Mask" "B.Paste")
			(net "GND")
		)
		(pad "2" smd circle
			(at -0.40005 0 270)
			(size 0 0)
			(layers "B.Cu" "B.Mask" "B.Paste")
			(net "FAN_PWR_EN_BUF_R")
		)
	)
	(footprint ""
		(layer "B.Cu")
		(at 265.049 -38.354 180)
		(property "Reference" "R5906"
			(at 0 0 0)
			(layer "B.SilkS")
			(hide yes)
			(effects
				(font
					(size 1.27 1.27)
				)
				(justify mirror)
			)
		)
		(property "Value" ""
			(at 0 0 0)
			(layer "B.Fab")
			(effects
				(font
					(size 1.27 1.27)
				)
				(justify mirror)
			)
		)
		(duplicate_pad_numbers_are_jumpers no)
		(fp_line
			(start 0.7874 0.4064)
			(end 0.7874 -0.4064)
			(stroke
				(width 0.1524)
				(type default)
			)
			(layer "B.SilkS")
		)
		(fp_line
			(start 0.7874 -0.4064)
			(end -0.7874 -0.4064)
			(stroke
				(width 0.1524)
				(type default)
			)
			(layer "B.SilkS")
		)
		(fp_line
			(start -0.7874 0.4064)
			(end 0.7874 0.4064)
			(stroke
				(width 0.1524)
				(type default)
			)
			(layer "B.SilkS")
		)
		(fp_line
			(start -0.7874 -0.4064)
			(end -0.7874 0.4064)
			(stroke
				(width 0.1524)
				(type default)
			)
			(layer "B.SilkS")
		)
		(fp_line
			(start 0.67945 0.3048)
			(end 0.67945 -0.305054)
			(stroke
				(width 0.1)
				(type default)
			)
			(layer "B.Fab")
		)
		(fp_line
			(start 0.67945 -0.305054)
			(end 0.12065 -0.305054)
			(stroke
				(width 0.1)
				(type default)
			)
			(layer "B.Fab")
		)
		(fp_line
			(start 0.12065 0.3048)
			(end 0.67945 0.3048)
			(stroke
				(width 0.1)
				(type default)
			)
			(layer "B.Fab")
		)
		(fp_line
			(start 0.12065 0.2794)
			(end 0.12065 0.3048)
			(stroke
				(width 0.1)
				(type default)
			)
			(layer "B.Fab")
		)
		(fp_line
			(start 0.12065 -0.2794)
			(end -0.12065 -0.2794)
			(stroke
				(width 0.1)
				(type default)
			)
			(layer "B.Fab")
		)
		(fp_line
			(start 0.12065 -0.305054)
			(end 0.12065 -0.2794)
			(stroke
				(width 0.1)
				(type default)
			)
			(layer "B.Fab")
		)
		(fp_line
			(start -0.120396 0.3048)
			(end -0.120396 0.2794)
			(stroke
				(width 0.1)
				(type default)
			)
			(layer "B.Fab")
		)
		(fp_line
			(start -0.120396 0.2794)
			(end 0.12065 0.2794)
			(stroke
				(width 0.1)
				(type default)
			)
			(layer "B.Fab")
		)
		(fp_line
			(start -0.12065 -0.2794)
			(end -0.12065 -0.3048)
			(stroke
				(width 0.1)
				(type default)
			)
			(layer "B.Fab")
		)
		(fp_line
			(start -0.12065 -0.3048)
			(end -0.67945 -0.3048)
			(stroke
				(width 0.1)
				(type default)
			)
			(layer "B.Fab")
		)
		(fp_line
			(start -0.67945 0.3048)
			(end -0.120396 0.3048)
			(stroke
				(width 0.1)
				(type default)
			)
			(layer "B.Fab")
		)
		(fp_line
			(start -0.67945 -0.3048)
			(end -0.67945 0.3048)
			(stroke
				(width 0.1)
				(type default)
			)
			(layer "B.Fab")
		)
		(pad "1" smd circle
			(at 0.40005 0)
			(size 0 0)
			(layers "B.Cu" "B.Mask" "B.Paste")
			(net "P52V_HS1_INTVCC")
		)
		(pad "2" smd circle
			(at -0.40005 0)
			(size 0 0)
			(layers "B.Cu" "B.Mask" "B.Paste")
			(net "P52V_HS1_ADR1")
		)
	)
	(footprint ""
		(layer "B.Cu")
		(at 56.642 -77.47 180)
		(property "Reference" "C62"
			(at 0 0 0)
			(layer "B.SilkS")
			(hide yes)
			(effects
				(font
					(size 1.27 1.27)
				)
				(justify mirror)
			)
		)
		(property "Value" ""
			(at 0 0 0)
			(layer "B.Fab")
			(effects
				(font
					(size 1.27 1.27)
				)
				(justify mirror)
			)
		)
		(duplicate_pad_numbers_are_jumpers no)
		(fp_line
			(start 0.7874 0.4064)
			(end 0.7874 -0.4064)
			(stroke
				(width 0.1524)
				(type default)
			)
			(layer "B.SilkS")
		)
		(fp_line
			(start 0.7874 -0.4064)
			(end -0.7874 -0.4064)
			(stroke
				(width 0.1524)
				(type default)
			)
			(layer "B.SilkS")
		)
		(fp_line
			(start -0.7874 0.4064)
			(end 0.7874 0.4064)
			(stroke
				(width 0.1524)
				(type default)
			)
			(layer "B.SilkS")
		)
		(fp_line
			(start -0.7874 -0.4064)
			(end -0.7874 0.4064)
			(stroke
				(width 0.1524)
				(type default)
			)
			(layer "B.SilkS")
		)
		(fp_line
			(start 0.67945 0.3048)
			(end 0.67945 -0.305054)
			(stroke
				(width 0.1)
				(type default)
			)
			(layer "B.Fab")
		)
		(fp_line
			(start 0.67945 -0.305054)
			(end 0.12065 -0.305054)
			(stroke
				(width 0.1)
				(type default)
			)
			(layer "B.Fab")
		)
		(fp_line
			(start 0.12065 0.3048)
			(end 0.67945 0.3048)
			(stroke
				(width 0.1)
				(type default)
			)
			(layer "B.Fab")
		)
		(fp_line
			(start 0.12065 0.2794)
			(end 0.12065 0.3048)
			(stroke
				(width 0.1)
				(type default)
			)
			(layer "B.Fab")
		)
		(fp_line
			(start 0.12065 -0.2794)
			(end -0.12065 -0.2794)
			(stroke
				(width 0.1)
				(type default)
			)
			(layer "B.Fab")
		)
		(fp_line
			(start 0.12065 -0.305054)
			(end 0.12065 -0.2794)
			(stroke
				(width 0.1)
				(type default)
			)
			(layer "B.Fab")
		)
		(fp_line
			(start -0.120396 0.3048)
			(end -0.120396 0.2794)
			(stroke
				(width 0.1)
				(type default)
			)
			(layer "B.Fab")
		)
		(fp_line
			(start -0.120396 0.2794)
			(end 0.12065 0.2794)
			(stroke
				(width 0.1)
				(type default)
			)
			(layer "B.Fab")
		)
		(fp_line
			(start -0.12065 -0.2794)
			(end -0.12065 -0.3048)
			(stroke
				(width 0.1)
				(type default)
			)
			(layer "B.Fab")
		)
		(fp_line
			(start -0.12065 -0.3048)
			(end -0.67945 -0.3048)
			(stroke
				(width 0.1)
				(type default)
			)
			(layer "B.Fab")
		)
		(fp_line
			(start -0.67945 0.3048)
			(end -0.120396 0.3048)
			(stroke
				(width 0.1)
				(type default)
			)
			(layer "B.Fab")
		)
		(fp_line
			(start -0.67945 -0.3048)
			(end -0.67945 0.3048)
			(stroke
				(width 0.1)
				(type default)
			)
			(layer "B.Fab")
		)
		(pad "1" smd circle
			(at 0.40005 0)
			(size 0 0)
			(layers "B.Cu" "B.Mask" "B.Paste")
			(net "P12V_BRICK3_ALERT_N")
		)
		(pad "2" smd circle
			(at -0.40005 0)
			(size 0 0)
			(layers "B.Cu" "B.Mask" "B.Paste")
			(net "GND")
		)
	)
	(footprint ""
		(layer "B.Cu")
		(at 144.653 -114.046 -90)
		(property "Reference" "R169"
			(at 0 0 90)
			(layer "B.SilkS")
			(hide yes)
			(effects
				(font
					(size 1.27 1.27)
				)
				(justify mirror)
			)
		)
		(property "Value" ""
			(at 0 0 90)
			(layer "B.Fab")
			(effects
				(font
					(size 1.27 1.27)
				)
				(justify mirror)
			)
		)
		(duplicate_pad_numbers_are_jumpers no)
		(fp_line
			(start -0.7874 0.4064)
			(end 0.7874 0.4064)
			(stroke
				(width 0.1524)
				(type default)
			)
			(layer "B.SilkS")
		)
		(fp_line
			(start 0.7874 0.4064)
			(end 0.7874 -0.4064)
			(stroke
				(width 0.1524)
				(type default)
			)
			(layer "B.SilkS")
		)
		(fp_line
			(start -0.7874 -0.4064)
			(end -0.7874 0.4064)
			(stroke
				(width 0.1524)
				(type default)
			)
			(layer "B.SilkS")
		)
		(fp_line
			(start 0.7874 -0.4064)
			(end -0.7874 -0.4064)
			(stroke
				(width 0.1524)
				(type default)
			)
			(layer "B.SilkS")
		)
		(fp_line
			(start -0.67945 0.3048)
			(end -0.120396 0.3048)
			(stroke
				(width 0.1)
				(type default)
			)
			(layer "B.Fab")
		)
		(fp_line
			(start -0.120396 0.3048)
			(end -0.120396 0.2794)
			(stroke
				(width 0.1)
				(type default)
			)
			(layer "B.Fab")
		)
		(fp_line
			(start 0.12065 0.3048)
			(end 0.67945 0.3048)
			(stroke
				(width 0.1)
				(type default)
			)
			(layer "B.Fab")
		)
		(fp_line
			(start 0.67945 0.3048)
			(end 0.67945 -0.305054)
			(stroke
				(width 0.1)
				(type default)
			)
			(layer "B.Fab")
		)
		(fp_line
			(start -0.120396 0.2794)
			(end 0.12065 0.2794)
			(stroke
				(width 0.1)
				(type default)
			)
			(layer "B.Fab")
		)
		(fp_line
			(start 0.12065 0.2794)
			(end 0.12065 0.3048)
			(stroke
				(width 0.1)
				(type default)
			)
			(layer "B.Fab")
		)
		(fp_line
			(start -0.12065 -0.2794)
			(end -0.12065 -0.3048)
			(stroke
				(width 0.1)
				(type default)
			)
			(layer "B.Fab")
		)
		(fp_line
			(start 0.12065 -0.2794)
			(end -0.12065 -0.2794)
			(stroke
				(width 0.1)
				(type default)
			)
			(layer "B.Fab")
		)
		(fp_line
			(start -0.67945 -0.3048)
			(end -0.67945 0.3048)
			(stroke
				(width 0.1)
				(type default)
			)
			(layer "B.Fab")
		)
		(fp_line
			(start -0.12065 -0.3048)
			(end -0.67945 -0.3048)
			(stroke
				(width 0.1)
				(type default)
			)
			(layer "B.Fab")
		)
		(fp_line
			(start 0.12065 -0.305054)
			(end 0.12065 -0.2794)
			(stroke
				(width 0.1)
				(type default)
			)
			(layer "B.Fab")
		)
		(fp_line
			(start 0.67945 -0.305054)
			(end 0.12065 -0.305054)
			(stroke
				(width 0.1)
				(type default)
			)
			(layer "B.Fab")
		)
		(pad "1" smd circle
			(at 0.40005 0 90)
			(size 0 0)
			(layers "B.Cu" "B.Mask" "B.Paste")
			(net "BRICK_P12V0_EN_R_N")
		)
		(pad "2" smd circle
			(at -0.40005 0 90)
			(size 0 0)
			(layers "B.Cu" "B.Mask" "B.Paste")
			(net "BRICK_P12V0_EN_N")
		)
	)
	(footprint ""
		(layer "B.Cu")
		(at 142.850108 -76.708 -90)
		(property "Reference" "PR50"
			(at 0 0 90)
			(layer "B.SilkS")
			(hide yes)
			(effects
				(font
					(size 1.27 1.27)
				)
				(justify mirror)
			)
		)
		(property "Value" ""
			(at 0 0 90)
			(layer "B.Fab")
			(effects
				(font
					(size 1.27 1.27)
				)
				(justify mirror)
			)
		)
		(duplicate_pad_numbers_are_jumpers no)
		(fp_line
			(start -0.7874 0.4064)
			(end 0.7874 0.4064)
			(stroke
				(width 0.1524)
				(type default)
			)
			(layer "B.SilkS")
		)
		(fp_line
			(start 0.7874 0.4064)
			(end 0.7874 -0.4064)
			(stroke
				(width 0.1524)
				(type default)
			)
			(layer "B.SilkS")
		)
		(fp_line
			(start -0.7874 -0.4064)
			(end -0.7874 0.4064)
			(stroke
				(width 0.1524)
				(type default)
			)
			(layer "B.SilkS")
		)
		(fp_line
			(start 0.7874 -0.4064)
			(end -0.7874 -0.4064)
			(stroke
				(width 0.1524)
				(type default)
			)
			(layer "B.SilkS")
		)
		(fp_line
			(start -0.67945 0.3048)
			(end -0.120396 0.3048)
			(stroke
				(width 0.1)
				(type default)
			)
			(layer "B.Fab")
		)
		(fp_line
			(start -0.120396 0.3048)
			(end -0.120396 0.2794)
			(stroke
				(width 0.1)
				(type default)
			)
			(layer "B.Fab")
		)
		(fp_line
			(start 0.12065 0.3048)
			(end 0.67945 0.3048)
			(stroke
				(width 0.1)
				(type default)
			)
			(layer "B.Fab")
		)
		(fp_line
			(start 0.67945 0.3048)
			(end 0.67945 -0.305054)
			(stroke
				(width 0.1)
				(type default)
			)
			(layer "B.Fab")
		)
		(fp_line
			(start -0.120396 0.2794)
			(end 0.12065 0.2794)
			(stroke
				(width 0.1)
				(type default)
			)
			(layer "B.Fab")
		)
		(fp_line
			(start 0.12065 0.2794)
			(end 0.12065 0.3048)
			(stroke
				(width 0.1)
				(type default)
			)
			(layer "B.Fab")
		)
		(fp_line
			(start -0.12065 -0.2794)
			(end -0.12065 -0.3048)
			(stroke
				(width 0.1)
				(type default)
			)
			(layer "B.Fab")
		)
		(fp_line
			(start 0.12065 -0.2794)
			(end -0.12065 -0.2794)
			(stroke
				(width 0.1)
				(type default)
			)
			(layer "B.Fab")
		)
		(fp_line
			(start -0.67945 -0.3048)
			(end -0.67945 0.3048)
			(stroke
				(width 0.1)
				(type default)
			)
			(layer "B.Fab")
		)
		(fp_line
			(start -0.12065 -0.3048)
			(end -0.67945 -0.3048)
			(stroke
				(width 0.1)
				(type default)
			)
			(layer "B.Fab")
		)
		(fp_line
			(start 0.12065 -0.305054)
			(end 0.12065 -0.2794)
			(stroke
				(width 0.1)
				(type default)
			)
			(layer "B.Fab")
		)
		(fp_line
			(start 0.67945 -0.305054)
			(end 0.12065 -0.305054)
			(stroke
				(width 0.1)
				(type default)
			)
			(layer "B.Fab")
		)
		(pad "1" smd rect
			(at 0.40005 0 270)
			(size 0.4572 0.508)
			(layers "B.Cu" "B.Mask" "B.Paste")
			(net "P12V_MB0_SENSE+")
		)
		(pad "2" smd rect
			(at -0.40005 0 270)
			(size 0.4572 0.508)
			(layers "B.Cu" "B.Mask" "B.Paste")
			(net "P12V_BRICK")
		)
	)
)
